(kicad_pcb
	(version 20260206)
	(generator "pcbnew")
	(generator_version "10.0")
	(general
		(thickness 1.6)
		(legacy_teardrops no)
	)
	(paper "A4")
	(title_block
		(title "Bryce Canyon_R.DPB_16317-1_OCP.brd")
		(comment 1 "Bryce Canyon / footprints 1224-1231 of 2099")
	)
	(layers
		(0 "F.Cu" signal "TOP")
		(4 "In1.Cu" signal "L2GND")
		(6 "In2.Cu" signal "L3")
		(8 "In3.Cu" signal "L4VCC")
		(10 "In4.Cu" signal "L5VCC")
		(12 "In5.Cu" signal "L6")
		(14 "In6.Cu" signal "L7GND")
		(2 "B.Cu" signal "BOTTOM")
		(9 "F.Adhes" user "F.Adhesive")
		(11 "B.Adhes" user "B.Adhesive")
		(13 "F.Paste" user "Package Geometry/Pastemask Top")
		(15 "B.Paste" user "Package Geometry/Pastemask Bottom")
		(5 "F.SilkS" user "Ref Des/Silkscreen Top")
		(7 "B.SilkS" user "Ref Des/Silkscreen Bottom")
		(1 "F.Mask" user "Board Geometry/Soldermask Top")
		(3 "B.Mask" user "Board Geometry/Soldermask Bottom")
		(17 "Dwgs.User" user "User.Drawings")
		(19 "Cmts.User" user "User.Comments")
		(21 "Eco1.User" user "User.Eco1")
		(23 "Eco2.User" user "User.Eco2")
		(25 "Edge.Cuts" user "Board Geometry/Outline")
		(27 "Margin" user)
		(31 "F.CrtYd" user "Package Geometry/Place Bound Top")
		(29 "B.CrtYd" user "Package Geometry/Place Bound Bottom")
		(35 "F.Fab" user "Ref Des/Assembly Top")
		(33 "B.Fab" user "Ref Des/Assembly Bottom")
	)
	(footprint ""
		(layer "F.Cu")
		(at 264.192258 -363.093)
		(property "Reference" "C79"
			(at 0 0 0)
			(layer "F.SilkS")
			(hide yes)
			(effects
				(font
					(size 1.27 1.27)
				)
			)
		)
		(property "Value" "SC1U16V3KX-5GP"
			(at 0 -2.8194 0)
			(unlocked yes)
			(layer "F.Fab")
			(hide yes)
			(effects
				(font
					(size 1.016 1.016)
					(thickness 0.1524)
				)
			)
		)
		(property "Device Type" "C603H36"
			(at 0 -4.3434 0)
			(unlocked yes)
			(layer "F.Fab")
			(hide yes)
			(effects
				(font
					(size 1.016 1.016)
					(thickness 0.1524)
				)
			)
		)
		(duplicate_pad_numbers_are_jumpers no)
		(fp_line
			(start 0.508 0)
			(end -0.508 0)
			(stroke
				(width 0.2032)
				(type default)
			)
			(layer "F.SilkS")
		)
		(fp_rect
			(start -0.5842 1.3335)
			(end 0.5842 -1.3335)
			(stroke
				(width 0)
				(type default)
			)
			(fill no)
			(layer "F.CrtYd")
		)
		(fp_rect
			(start -0.5842 1.3335)
			(end 0.5842 -1.3335)
			(stroke
				(width 0)
				(type default)
			)
			(fill no)
			(layer "F.Fab")
		)
		(pad "1" smd custom
			(at 0 -0.762)
			(size 0.2159 0.2159)
			(layers "F.Cu" "F.Mask" "F.Paste")
			(net "P3V3_IN_BIAS")
			(options
				(clearance outline)
				(anchor circle)
			)
			(primitives
				(gr_poly
					(pts
						(arc
							(start -0.3302 -0.4318)
							(mid -0.402042 -0.402042)
							(end -0.4318 -0.3302)
						)
						(arc
							(start -0.4318 0.3302)
							(mid -0.402042 0.402042)
							(end -0.3302 0.4318)
						)
						(arc
							(start 0.3302 0.4318)
							(mid 0.402042 0.402042)
							(end 0.4318 0.3302)
						)
						(arc
							(start 0.4318 -0.3302)
							(mid 0.402042 -0.402042)
							(end 0.3302 -0.4318)
						)
					)
					(width 0)
					(fill yes)
				)
			)
		)
		(pad "2" smd custom
			(at 0 0.762)
			(size 0.2159 0.2159)
			(layers "F.Cu" "F.Mask" "F.Paste")
			(net "GND")
			(options
				(clearance outline)
				(anchor circle)
			)
			(primitives
				(gr_poly
					(pts
						(arc
							(start -0.3302 -0.4318)
							(mid -0.402042 -0.402042)
							(end -0.4318 -0.3302)
						)
						(arc
							(start -0.4318 0.3302)
							(mid -0.402042 0.402042)
							(end -0.3302 0.4318)
						)
						(arc
							(start 0.3302 0.4318)
							(mid 0.402042 0.402042)
							(end 0.4318 0.3302)
						)
						(arc
							(start 0.4318 -0.3302)
							(mid 0.402042 -0.402042)
							(end 0.3302 -0.4318)
						)
					)
					(width 0)
					(fill yes)
				)
			)
		)
	)
	(footprint ""
		(layer "F.Cu")
		(at 38.956996 -369.697)
		(property "Reference" "C519"
			(at 0 0 0)
			(layer "F.SilkS")
			(hide yes)
			(effects
				(font
					(size 1.27 1.27)
				)
			)
		)
		(property "Value" "SCD1U25V2KX-2-GP"
			(at 1.1811 -2.7051 0)
			(unlocked yes)
			(layer "F.Fab")
			(hide yes)
			(effects
				(font
					(size 1.016 1.016)
					(thickness 0.1524)
				)
			)
		)
		(property "Device Type" "C402H22"
			(at 1.1811 -4.2291 0)
			(unlocked yes)
			(layer "F.Fab")
			(hide yes)
			(effects
				(font
					(size 1.016 1.016)
					(thickness 0.1524)
				)
			)
		)
		(duplicate_pad_numbers_are_jumpers no)
		(fp_rect
			(start -0.4318 0.9525)
			(end 0.4318 -0.9525)
			(stroke
				(width 0)
				(type default)
			)
			(fill no)
			(layer "F.CrtYd")
		)
		(fp_rect
			(start -0.4318 0.9525)
			(end 0.4318 -0.9525)
			(stroke
				(width 0)
				(type default)
			)
			(fill no)
			(layer "F.Fab")
		)
		(pad "1" smd custom
			(at 0 -0.4445)
			(size 0.1524 0.1524)
			(layers "F.Cu" "F.Mask" "F.Paste")
			(net "FAN_0_TACH0")
			(options
				(clearance outline)
				(anchor circle)
			)
			(primitives
				(gr_poly
					(pts
						(arc
							(start 0.3048 -0.2032)
							(mid 0.275042 -0.275042)
							(end 0.2032 -0.3048)
						)
						(arc
							(start -0.2032 -0.3048)
							(mid -0.275042 -0.275042)
							(end -0.3048 -0.2032)
						)
						(arc
							(start -0.3048 0.2032)
							(mid -0.275042 0.275042)
							(end -0.2032 0.3048)
						)
						(arc
							(start 0.2032 0.3048)
							(mid 0.275042 0.275042)
							(end 0.3048 0.2032)
						)
					)
					(width 0)
					(fill yes)
				)
			)
		)
		(pad "2" smd custom
			(at 0 0.4445)
			(size 0.1524 0.1524)
			(layers "F.Cu" "F.Mask" "F.Paste")
			(net "GND")
			(options
				(clearance outline)
				(anchor circle)
			)
			(primitives
				(gr_poly
					(pts
						(arc
							(start 0.3048 -0.2032)
							(mid 0.275042 -0.275042)
							(end 0.2032 -0.3048)
						)
						(arc
							(start -0.2032 -0.3048)
							(mid -0.275042 -0.275042)
							(end -0.3048 -0.2032)
						)
						(arc
							(start -0.3048 0.2032)
							(mid -0.275042 0.275042)
							(end -0.2032 0.3048)
						)
						(arc
							(start 0.2032 0.3048)
							(mid 0.275042 0.275042)
							(end 0.3048 0.2032)
						)
					)
					(width 0)
					(fill yes)
				)
			)
		)
	)
	(footprint ""
		(layer "F.Cu")
		(at 168.91 -367.919 -90)
		(property "Reference" "C541"
			(at 0 0 270)
			(layer "F.SilkS")
			(hide yes)
			(effects
				(font
					(size 1.27 1.27)
				)
			)
		)
		(property "Value" "SC1U25V3KX-GP"
			(at 0 -2.8194 270)
			(unlocked yes)
			(layer "F.Fab")
			(hide yes)
			(effects
				(font
					(size 1.016 1.016)
					(thickness 0.1524)
				)
			)
		)
		(property "Device Type" "C603H36"
			(at 0 -4.3434 270)
			(unlocked yes)
			(layer "F.Fab")
			(hide yes)
			(effects
				(font
					(size 1.016 1.016)
					(thickness 0.1524)
				)
			)
		)
		(duplicate_pad_numbers_are_jumpers no)
		(fp_line
			(start 0.508 0)
			(end -0.508 0)
			(stroke
				(width 0.2032)
				(type default)
			)
			(layer "F.SilkS")
		)
		(fp_rect
			(start -0.5842 1.3335)
			(end 0.5842 -1.3335)
			(stroke
				(width 0)
				(type default)
			)
			(fill no)
			(layer "F.CrtYd")
		)
		(fp_rect
			(start -0.5842 1.3335)
			(end 0.5842 -1.3335)
			(stroke
				(width 0)
				(type default)
			)
			(fill no)
			(layer "F.Fab")
		)
		(pad "1" smd custom
			(at 0 -0.762 270)
			(size 0.2159 0.2159)
			(layers "F.Cu" "F.Mask" "F.Paste")
			(net "MB0_P12V_HS")
			(options
				(clearance outline)
				(anchor circle)
			)
			(primitives
				(gr_poly
					(pts
						(arc
							(start -0.3302 -0.4318)
							(mid -0.402042 -0.402042)
							(end -0.4318 -0.3302)
						)
						(arc
							(start -0.4318 0.3302)
							(mid -0.402042 0.402042)
							(end -0.3302 0.4318)
						)
						(arc
							(start 0.3302 0.4318)
							(mid 0.402042 0.402042)
							(end 0.4318 0.3302)
						)
						(arc
							(start 0.4318 -0.3302)
							(mid 0.402042 -0.402042)
							(end 0.3302 -0.4318)
						)
					)
					(width 0)
					(fill yes)
				)
			)
		)
		(pad "2" smd custom
			(at 0 0.762 270)
			(size 0.2159 0.2159)
			(layers "F.Cu" "F.Mask" "F.Paste")
			(net "AGND_CURRENT_MON")
			(options
				(clearance outline)
				(anchor circle)
			)
			(primitives
				(gr_poly
					(pts
						(arc
							(start -0.3302 -0.4318)
							(mid -0.402042 -0.402042)
							(end -0.4318 -0.3302)
						)
						(arc
							(start -0.4318 0.3302)
							(mid -0.402042 0.402042)
							(end -0.3302 0.4318)
						)
						(arc
							(start 0.3302 0.4318)
							(mid 0.402042 0.402042)
							(end 0.4318 0.3302)
						)
						(arc
							(start 0.4318 -0.3302)
							(mid 0.402042 -0.402042)
							(end 0.3302 -0.4318)
						)
					)
					(width 0)
					(fill yes)
				)
			)
		)
	)
	(footprint ""
		(layer "F.Cu")
		(at 181.3306 -373.7864 -90)
		(property "Reference" "R997"
			(at 0 0 270)
			(layer "F.SilkS")
			(hide yes)
			(effects
				(font
					(size 1.27 1.27)
				)
			)
		)
		(property "Value" "10KR2F-2-GP"
			(at 0.064008 -3.993896 270)
			(unlocked yes)
			(layer "F.Fab")
			(hide yes)
			(effects
				(font
					(size 1.016 1.016)
					(thickness 0.1524)
				)
			)
		)
		(property "Device Type" "R402H16"
			(at 0.064008 -5.517896 270)
			(unlocked yes)
			(layer "F.Fab")
			(hide yes)
			(effects
				(font
					(size 1.016 1.016)
					(thickness 0.1524)
				)
			)
		)
		(duplicate_pad_numbers_are_jumpers no)
		(fp_line
			(start -0.508 -0.9398)
			(end -0.508 0.9398)
			(stroke
				(width 0.1524)
				(type default)
			)
			(layer "F.SilkS")
		)
		(fp_line
			(start 0.508 -0.9398)
			(end -0.508 -0.9398)
			(stroke
				(width 0.1524)
				(type default)
			)
			(layer "F.SilkS")
		)
		(fp_rect
			(start -0.508 0.9398)
			(end 0.508 -0.9398)
			(stroke
				(width 0)
				(type default)
			)
			(fill no)
			(layer "F.CrtYd")
		)
		(fp_rect
			(start -0.508 0.9398)
			(end 0.508 -0.9398)
			(stroke
				(width 0)
				(type default)
			)
			(fill no)
			(layer "F.Fab")
		)
		(pad "1" smd custom
			(at 0 -0.4445 270)
			(size 0.1397 0.1397)
			(layers "F.Cu" "F.Mask" "F.Paste")
			(net "P12V_IN")
			(options
				(clearance outline)
				(anchor circle)
			)
			(primitives
				(gr_poly
					(pts
						(arc
							(start -0.1778 -0.2794)
							(mid -0.249642 -0.249642)
							(end -0.2794 -0.1778)
						)
						(arc
							(start -0.2794 0.1778)
							(mid -0.249642 0.249642)
							(end -0.1778 0.2794)
						)
						(arc
							(start 0.1778 0.2794)
							(mid 0.249642 0.249642)
							(end 0.2794 0.1778)
						)
						(arc
							(start 0.2794 -0.1778)
							(mid 0.249642 -0.249642)
							(end 0.1778 -0.2794)
						)
					)
					(width 0)
					(fill yes)
				)
			)
		)
		(pad "2" smd custom
			(at 0 0.4445 270)
			(size 0.1397 0.1397)
			(layers "F.Cu" "F.Mask" "F.Paste")
			(net "P12V_IN_PGOOD")
			(options
				(clearance outline)
				(anchor circle)
			)
			(primitives
				(gr_poly
					(pts
						(arc
							(start -0.1778 -0.2794)
							(mid -0.249642 -0.249642)
							(end -0.2794 -0.1778)
						)
						(arc
							(start -0.2794 0.1778)
							(mid -0.249642 0.249642)
							(end -0.1778 0.2794)
						)
						(arc
							(start 0.1778 0.2794)
							(mid 0.249642 0.249642)
							(end 0.2794 0.1778)
						)
						(arc
							(start 0.2794 -0.1778)
							(mid 0.249642 -0.249642)
							(end 0.1778 -0.2794)
						)
					)
					(width 0)
					(fill yes)
				)
			)
		)
	)
	(footprint ""
		(layer "F.Cu")
		(at 475.3356 -33.655 -90)
		(property "Reference" "C485"
			(at 0 0 270)
			(layer "F.SilkS")
			(hide yes)
			(effects
				(font
					(size 1.27 1.27)
				)
			)
		)
		(property "Value" "SC1U16V3KX-5GP"
			(at 0 -2.8194 270)
			(unlocked yes)
			(layer "F.Fab")
			(hide yes)
			(effects
				(font
					(size 1.016 1.016)
					(thickness 0.1524)
				)
			)
		)
		(property "Device Type" "C603H36"
			(at 0 -4.3434 270)
			(unlocked yes)
			(layer "F.Fab")
			(hide yes)
			(effects
				(font
					(size 1.016 1.016)
					(thickness 0.1524)
				)
			)
		)
		(duplicate_pad_numbers_are_jumpers no)
		(fp_line
			(start 0.508 0)
			(end -0.508 0)
			(stroke
				(width 0.2032)
				(type default)
			)
			(layer "F.SilkS")
		)
		(fp_rect
			(start -0.5842 1.3335)
			(end 0.5842 -1.3335)
			(stroke
				(width 0)
				(type default)
			)
			(fill no)
			(layer "F.CrtYd")
		)
		(fp_rect
			(start -0.5842 1.3335)
			(end 0.5842 -1.3335)
			(stroke
				(width 0)
				(type default)
			)
			(fill no)
			(layer "F.Fab")
		)
		(pad "1" smd custom
			(at 0 -0.762 270)
			(size 0.2159 0.2159)
			(layers "F.Cu" "F.Mask" "F.Paste")
			(net "P5V_HDD35")
			(options
				(clearance outline)
				(anchor circle)
			)
			(primitives
				(gr_poly
					(pts
						(arc
							(start -0.3302 -0.4318)
							(mid -0.402042 -0.402042)
							(end -0.4318 -0.3302)
						)
						(arc
							(start -0.4318 0.3302)
							(mid -0.402042 0.402042)
							(end -0.3302 0.4318)
						)
						(arc
							(start 0.3302 0.4318)
							(mid 0.402042 0.402042)
							(end 0.4318 0.3302)
						)
						(arc
							(start 0.4318 -0.3302)
							(mid 0.402042 -0.402042)
							(end 0.3302 -0.4318)
						)
					)
					(width 0)
					(fill yes)
				)
			)
		)
		(pad "2" smd custom
			(at 0 0.762 270)
			(size 0.2159 0.2159)
			(layers "F.Cu" "F.Mask" "F.Paste")
			(net "GND")
			(options
				(clearance outline)
				(anchor circle)
			)
			(primitives
				(gr_poly
					(pts
						(arc
							(start -0.3302 -0.4318)
							(mid -0.402042 -0.402042)
							(end -0.4318 -0.3302)
						)
						(arc
							(start -0.4318 0.3302)
							(mid -0.402042 0.402042)
							(end -0.3302 0.4318)
						)
						(arc
							(start 0.3302 0.4318)
							(mid 0.402042 0.402042)
							(end 0.4318 0.3302)
						)
						(arc
							(start 0.4318 -0.3302)
							(mid 0.402042 -0.402042)
							(end 0.3302 -0.4318)
						)
					)
					(width 0)
					(fill yes)
				)
			)
		)
	)
	(footprint ""
		(layer "F.Cu")
		(at 268.224 -212.8012 90)
		(property "Reference" "R11"
			(at 0 0 90)
			(layer "F.SilkS")
			(hide yes)
			(effects
				(font
					(size 1.27 1.27)
				)
			)
		)
		(property "Value" "1KR2J-1-GP"
			(at 0.064008 -3.993896 90)
			(unlocked yes)
			(layer "F.Fab")
			(hide yes)
			(effects
				(font
					(size 1.016 1.016)
					(thickness 0.1524)
				)
			)
		)
		(property "Device Type" "R402H16"
			(at 0.064008 -5.517896 90)
			(unlocked yes)
			(layer "F.Fab")
			(hide yes)
			(effects
				(font
					(size 1.016 1.016)
					(thickness 0.1524)
				)
			)
		)
		(duplicate_pad_numbers_are_jumpers no)
		(fp_line
			(start 0.508 -0.9398)
			(end -0.508 -0.9398)
			(stroke
				(width 0.1524)
				(type default)
			)
			(layer "F.SilkS")
		)
		(fp_line
			(start -0.508 -0.9398)
			(end -0.508 0.9398)
			(stroke
				(width 0.1524)
				(type default)
			)
			(layer "F.SilkS")
		)
		(fp_rect
			(start -0.508 0.9398)
			(end 0.508 -0.9398)
			(stroke
				(width 0)
				(type default)
			)
			(fill no)
			(layer "F.CrtYd")
		)
		(fp_rect
			(start -0.508 0.9398)
			(end 0.508 -0.9398)
			(stroke
				(width 0)
				(type default)
			)
			(fill no)
			(layer "F.Fab")
		)
		(pad "1" smd custom
			(at 0 -0.4445 90)
			(size 0.1397 0.1397)
			(layers "F.Cu" "F.Mask" "F.Paste")
			(net "P3V3_STBY_B")
			(options
				(clearance outline)
				(anchor circle)
			)
			(primitives
				(gr_poly
					(pts
						(arc
							(start -0.1778 -0.2794)
							(mid -0.249642 -0.249642)
							(end -0.2794 -0.1778)
						)
						(arc
							(start -0.2794 0.1778)
							(mid -0.249642 0.249642)
							(end -0.1778 0.2794)
						)
						(arc
							(start 0.1778 0.2794)
							(mid 0.249642 0.249642)
							(end 0.2794 0.1778)
						)
						(arc
							(start 0.2794 -0.1778)
							(mid 0.249642 -0.249642)
							(end 0.1778 -0.2794)
						)
					)
					(width 0)
					(fill yes)
				)
			)
		)
		(pad "2" smd custom
			(at 0 0.4445 90)
			(size 0.1397 0.1397)
			(layers "F.Cu" "F.Mask" "F.Paste")
			(net "I2C_DRIVE_B_INS_SDA")
			(options
				(clearance outline)
				(anchor circle)
			)
			(primitives
				(gr_poly
					(pts
						(arc
							(start -0.1778 -0.2794)
							(mid -0.249642 -0.249642)
							(end -0.2794 -0.1778)
						)
						(arc
							(start -0.2794 0.1778)
							(mid -0.249642 0.249642)
							(end -0.1778 0.2794)
						)
						(arc
							(start 0.1778 0.2794)
							(mid 0.249642 0.249642)
							(end 0.2794 0.1778)
						)
						(arc
							(start 0.2794 -0.1778)
							(mid 0.249642 -0.249642)
							(end 0.1778 -0.2794)
						)
					)
					(width 0)
					(fill yes)
				)
			)
		)
	)
	(footprint ""
		(layer "F.Cu")
		(at 368.808 -18.796 90)
		(property "Reference" "D31"
			(at 0 0 90)
			(layer "F.SilkS")
			(hide yes)
			(effects
				(font
					(size 1.27 1.27)
				)
			)
		)
		(property "Value" "RB551V30-GP"
			(at 0 -6.7818 90)
			(unlocked yes)
			(layer "F.Fab")
			(hide yes)
			(effects
				(font
					(size 1.016 1.016)
					(thickness 0.1524)
				)
			)
		)
		(property "Device Type" "SOD323AKH38"
			(at 0 -8.6868 90)
			(unlocked yes)
			(layer "F.Fab")
			(hide yes)
			(effects
				(font
					(size 1.016 1.016)
					(thickness 0.1524)
				)
			)
		)
		(duplicate_pad_numbers_are_jumpers no)
		(fp_line
			(start 0.889 -1.9304)
			(end 0.889 2.159)
			(stroke
				(width 0.1524)
				(type default)
			)
			(layer "F.SilkS")
		)
		(fp_line
			(start -0.889 -1.9304)
			(end 0.889 -1.9304)
			(stroke
				(width 0.1524)
				(type default)
			)
			(layer "F.SilkS")
		)
		(fp_line
			(start 0.762 2.0574)
			(end -0.762 2.0574)
			(stroke
				(width 0.508)
				(type default)
			)
			(layer "F.SilkS")
		)
		(fp_line
			(start 0.889 2.159)
			(end -0.889 2.159)
			(stroke
				(width 0.1524)
				(type default)
			)
			(layer "F.SilkS")
		)
		(fp_line
			(start -0.889 2.159)
			(end -0.889 -1.9304)
			(stroke
				(width 0.1524)
				(type default)
			)
			(layer "F.SilkS")
		)
		(fp_rect
			(start -1.016 2.3114)
			(end 1.016 -2.0066)
			(stroke
				(width 0)
				(type default)
			)
			(fill no)
			(layer "F.CrtYd")
		)
		(fp_poly
			(pts
				(xy -1.016 -2.0066) (xy 1.016 -2.0066) (xy 1.016 2.3114) (xy -1.016 2.3114)
			)
			(stroke
				(width 0)
				(type default)
			)
			(fill no)
			(layer "F.Fab")
		)
		(pad "A" smd rect
			(at 0 -1.143 90)
			(size 0.5588 1.016)
			(layers "F.Cu" "F.Mask" "F.Paste")
			(net "SW_HDD_R31")
		)
		(pad "K" smd rect
			(at 0 1.143 90)
			(size 0.5588 1.016)
			(layers "F.Cu" "F.Mask" "F.Paste")
			(net "SW_HDD_N31")
		)
	)
	(footprint ""
		(layer "F.Cu")
		(at 370.205 -142.875 -90)
		(property "Reference" "R522"
			(at 0 0 270)
			(layer "F.SilkS")
			(hide yes)
			(effects
				(font
					(size 1.27 1.27)
				)
			)
		)
		(property "Value" "300KR2F-GP"
			(at 0.064008 -3.993896 270)
			(unlocked yes)
			(layer "F.Fab")
			(hide yes)
			(effects
				(font
					(size 1.016 1.016)
					(thickness 0.1524)
				)
			)
		)
		(property "Device Type" "R402H16"
			(at 0.064008 -5.517896 270)
			(unlocked yes)
			(layer "F.Fab")
			(hide yes)
			(effects
				(font
					(size 1.016 1.016)
					(thickness 0.1524)
				)
			)
		)
		(duplicate_pad_numbers_are_jumpers no)
		(fp_line
			(start -0.508 -0.9398)
			(end -0.508 0.9398)
			(stroke
				(width 0.1524)
				(type default)
			)
			(layer "F.SilkS")
		)
		(fp_line
			(start 0.508 -0.9398)
			(end -0.508 -0.9398)
			(stroke
				(width 0.1524)
				(type default)
			)
			(layer "F.SilkS")
		)
		(fp_rect
			(start -0.508 0.9398)
			(end 0.508 -0.9398)
			(stroke
				(width 0)
				(type default)
			)
			(fill no)
			(layer "F.CrtYd")
		)
		(fp_rect
			(start -0.508 0.9398)
			(end 0.508 -0.9398)
			(stroke
				(width 0)
				(type default)
			)
			(fill no)
			(layer "F.Fab")
		)
		(pad "1" smd custom
			(at 0 -0.4445 270)
			(size 0.1397 0.1397)
			(layers "F.Cu" "F.Mask" "F.Paste")
			(net "SW_HDD_N19")
			(options
				(clearance outline)
				(anchor circle)
			)
			(primitives
				(gr_poly
					(pts
						(arc
							(start -0.1778 -0.2794)
							(mid -0.249642 -0.249642)
							(end -0.2794 -0.1778)
						)
						(arc
							(start -0.2794 0.1778)
							(mid -0.249642 0.249642)
							(end -0.1778 0.2794)
						)
						(arc
							(start 0.1778 0.2794)
							(mid 0.249642 0.249642)
							(end 0.2794 0.1778)
						)
						(arc
							(start 0.2794 -0.1778)
							(mid 0.249642 -0.249642)
							(end 0.1778 -0.2794)
						)
					)
					(width 0)
					(fill yes)
				)
			)
		)
		(pad "2" smd custom
			(at 0 0.4445 270)
			(size 0.1397 0.1397)
			(layers "F.Cu" "F.Mask" "F.Paste")
			(net "P12V_B")
			(options
				(clearance outline)
				(anchor circle)
			)
			(primitives
				(gr_poly
					(pts
						(arc
							(start -0.1778 -0.2794)
							(mid -0.249642 -0.249642)
							(end -0.2794 -0.1778)
						)
						(arc
							(start -0.2794 0.1778)
							(mid -0.249642 0.249642)
							(end -0.1778 0.2794)
						)
						(arc
							(start 0.1778 0.2794)
							(mid 0.249642 0.249642)
							(end 0.2794 0.1778)
						)
						(arc
							(start 0.2794 -0.1778)
							(mid 0.249642 -0.249642)
							(end 0.1778 -0.2794)
						)
					)
					(width 0)
					(fill yes)
				)
			)
		)
	)
)
